# T6G (Grand Teton) — schematic netlist excerpt (pin names and nets, part order shuffled) for the footprints in the layout excerpt that follows; sources: Cadence DE-HDL packaged netlist, KiCad conversion of 04192023_DAF0TMB3IC0_F0TG_MB_C_brd_V02_OCP.brd

R1140  Q_RES  27.4 1% CHIP  pkg 0402LF  page 133 : A = CLK_50M_BMC_MAC_R ; B = CLK_50M_RMII_BMC_OCP

U92  SN74LVC1G07DBVR  IC  pkg SMLF  page 84
  NC  = NC
  A  = SCM_IRQ_1V8_N
  GND  = GND
  Y  = SCM_IRQ_R_N
  VCC  = P1V8_AUX

(kicad_pcb
	(version 20260206)
	(generator "pcbnew")
	(generator_version "10.0")
	(general
		(thickness 1.6)
		(legacy_teardrops no)
	)
	(paper "A4")
	(title_block
		(title "04192023_DAF0TMB3IC0_F0TG_MB_C_brd_V02_OCP.brd")
		(comment 1 "Grand Teton / footprints 2749-2750 of 8354")
	)
	(layers
		(0 "F.Cu" signal "TOP")
		(4 "In1.Cu" signal "GND")
		(6 "In2.Cu" signal "IN1")
		(8 "In3.Cu" signal "GND1")
		(10 "In4.Cu" signal "IN2")
		(12 "In5.Cu" signal "GND2")
		(14 "In6.Cu" signal "IN3")
		(16 "In7.Cu" signal "GND3")
		(18 "In8.Cu" signal "VCC")
		(20 "In9.Cu" signal "VCC1")
		(22 "In10.Cu" signal "GND4")
		(24 "In11.Cu" signal "IN4")
		(26 "In12.Cu" signal "GND5")
		(28 "In13.Cu" signal "IN5")
		(30 "In14.Cu" signal "GND6")
		(32 "In15.Cu" signal "IN6")
		(34 "In16.Cu" signal "GND7")
		(2 "B.Cu" signal "BOTTOM")
		(9 "F.Adhes" user "F.Adhesive")
		(11 "B.Adhes" user "B.Adhesive")
		(13 "F.Paste" user "Package Geometry/Pastemask Top")
		(15 "B.Paste" user "Package Geometry/Pastemask Bottom")
		(5 "F.SilkS" user "Ref Des/Silkscreen Top")
		(7 "B.SilkS" user "Ref Des/Silkscreen Bottom")
		(1 "F.Mask" user "Board Geometry/Soldermask Top")
		(3 "B.Mask" user "Board Geometry/Soldermask Bottom")
		(17 "Dwgs.User" user "User.Drawings")
		(19 "Cmts.User" user "User.Comments")
		(21 "Eco1.User" user "User.Eco1")
		(23 "Eco2.User" user "User.Eco2")
		(25 "Edge.Cuts" user "Board Geometry/Outline")
		(27 "Margin" user)
		(31 "F.CrtYd" user "Package Geometry/Place Bound Top")
		(29 "B.CrtYd" user "Package Geometry/Place Bound Bottom")
		(35 "F.Fab" user "Ref Des/Assembly Top")
		(33 "B.Fab" user "Ref Des/Assembly Bottom")
	)
	(footprint ""
		(layer "F.Cu")
		(at 213.061804 -22.974554 180)
		(property "Reference" "R1140"
			(at 0 0 180)
			(layer "F.SilkS")
			(hide yes)
			(effects
				(font
					(size 1.27 1.27)
				)
			)
		)
		(property "Value" ""
			(at 0 0 180)
			(layer "F.Fab")
			(effects
				(font
					(size 1.27 1.27)
				)
			)
		)
		(duplicate_pad_numbers_are_jumpers no)
		(fp_line
			(start 0.7874 0.4064)
			(end -0.7874 0.4064)
			(stroke
				(width 0.1524)
				(type default)
			)
			(layer "F.SilkS")
		)
		(fp_line
			(start 0.7874 -0.4064)
			(end 0.7874 0.4064)
			(stroke
				(width 0.1524)
				(type default)
			)
			(layer "F.SilkS")
		)
		(fp_line
			(start -0.7874 0.4064)
			(end -0.7874 -0.4064)
			(stroke
				(width 0.1524)
				(type default)
			)
			(layer "F.SilkS")
		)
		(fp_line
			(start -0.7874 -0.4064)
			(end 0.7874 -0.4064)
			(stroke
				(width 0.1524)
				(type default)
			)
			(layer "F.SilkS")
		)
		(fp_line
			(start 0.67945 0.3048)
			(end 0.120396 0.3048)
			(stroke
				(width 0.1)
				(type default)
			)
			(layer "F.Fab")
		)
		(fp_line
			(start 0.67945 -0.3048)
			(end 0.67945 0.3048)
			(stroke
				(width 0.1)
				(type default)
			)
			(layer "F.Fab")
		)
		(fp_line
			(start 0.12065 -0.2794)
			(end 0.12065 -0.3048)
			(stroke
				(width 0.1)
				(type default)
			)
			(layer "F.Fab")
		)
		(fp_line
			(start 0.12065 -0.3048)
			(end 0.67945 -0.3048)
			(stroke
				(width 0.1)
				(type default)
			)
			(layer "F.Fab")
		)
		(fp_line
			(start 0.120396 0.3048)
			(end 0.120396 0.2794)
			(stroke
				(width 0.1)
				(type default)
			)
			(layer "F.Fab")
		)
		(fp_line
			(start 0.120396 0.2794)
			(end -0.12065 0.2794)
			(stroke
				(width 0.1)
				(type default)
			)
			(layer "F.Fab")
		)
		(fp_line
			(start -0.12065 0.3048)
			(end -0.67945 0.3048)
			(stroke
				(width 0.1)
				(type default)
			)
			(layer "F.Fab")
		)
		(fp_line
			(start -0.12065 0.2794)
			(end -0.12065 0.3048)
			(stroke
				(width 0.1)
				(type default)
			)
			(layer "F.Fab")
		)
		(fp_line
			(start -0.12065 -0.2794)
			(end 0.12065 -0.2794)
			(stroke
				(width 0.1)
				(type default)
			)
			(layer "F.Fab")
		)
		(fp_line
			(start -0.12065 -0.305054)
			(end -0.12065 -0.2794)
			(stroke
				(width 0.1)
				(type default)
			)
			(layer "F.Fab")
		)
		(fp_line
			(start -0.67945 0.3048)
			(end -0.67945 -0.305054)
			(stroke
				(width 0.1)
				(type default)
			)
			(layer "F.Fab")
		)
		(fp_line
			(start -0.67945 -0.305054)
			(end -0.12065 -0.305054)
			(stroke
				(width 0.1)
				(type default)
			)
			(layer "F.Fab")
		)
		(pad "1" smd circle
			(at -0.40005 0 180)
			(size 0 0)
			(layers "F.Cu" "F.Mask" "F.Paste")
			(net "CLK_50M_BMC_MAC_R")
		)
		(pad "2" smd circle
			(at 0.40005 0 180)
			(size 0 0)
			(layers "F.Cu" "F.Mask" "F.Paste")
			(net "CLK_50M_RMII_BMC_OCP")
		)
	)
	(footprint ""
		(layer "F.Cu")
		(at 152.316434 -110.731046)
		(property "Reference" "U92"
			(at -5.426202 -1.786636 0)
			(unlocked yes)
			(layer "F.SilkS")
			(effects
				(font
					(size 0.7874 0.5842)
					(thickness 0.1524)
				)
				(justify left)
			)
		)
		(property "Value" ""
			(at 0 0 0)
			(layer "F.Fab")
			(effects
				(font
					(size 1.27 1.27)
				)
			)
		)
		(duplicate_pad_numbers_are_jumpers no)
		(fp_line
			(start -2.0574 -1.651)
			(end -0.381 -1.651)
			(stroke
				(width 0.1524)
				(type default)
			)
			(layer "F.SilkS")
		)
		(fp_line
			(start -2.0574 1.651)
			(end -2.0574 -1.651)
			(stroke
				(width 0.1524)
				(type default)
			)
			(layer "F.SilkS")
		)
		(fp_line
			(start -0.381 -1.651)
			(end 0 -1.016)
			(stroke
				(width 0.1524)
				(type default)
			)
			(layer "F.SilkS")
		)
		(fp_line
			(start 0 -1.016)
			(end 0.381 -1.651)
			(stroke
				(width 0.1524)
				(type default)
			)
			(layer "F.SilkS")
		)
		(fp_line
			(start 0.381 -1.651)
			(end 2.0574 -1.651)
			(stroke
				(width 0.1524)
				(type default)
			)
			(layer "F.SilkS")
		)
		(fp_line
			(start 2.0574 -1.651)
			(end 2.0574 1.651)
			(stroke
				(width 0.1524)
				(type default)
			)
			(layer "F.SilkS")
		)
		(fp_line
			(start 2.0574 1.651)
			(end -2.0574 1.651)
			(stroke
				(width 0.1524)
				(type default)
			)
			(layer "F.SilkS")
		)
		(fp_poly
			(pts
				(xy -2.159 -1.016) (xy -2.71272 -0.719328) (xy -2.71272 -1.344168)
			)
			(stroke
				(width 0)
				(type default)
			)
			(fill yes)
			(layer "F.SilkS")
		)
		(fp_line
			(start -1.599946 -1.199896)
			(end -0.899922 -1.199896)
			(stroke
				(width 0.1)
				(type default)
			)
			(layer "F.Fab")
		)
		(fp_line
			(start -1.599946 1.199896)
			(end -1.599946 -1.199896)
			(stroke
				(width 0.1)
				(type default)
			)
			(layer "F.Fab")
		)
		(fp_line
			(start -0.899922 -1.549908)
			(end 0.899922 -1.549908)
			(stroke
				(width 0.1)
				(type default)
			)
			(layer "F.Fab")
		)
		(fp_line
			(start -0.899922 -1.199896)
			(end -0.899922 -1.549908)
			(stroke
				(width 0.1)
				(type default)
			)
			(layer "F.Fab")
		)
		(fp_line
			(start -0.899922 1.199896)
			(end -1.599946 1.199896)
			(stroke
				(width 0.1)
				(type default)
			)
			(layer "F.Fab")
		)
		(fp_line
			(start -0.899922 1.549908)
			(end -0.899922 1.199896)
			(stroke
				(width 0.1)
				(type default)
			)
			(layer "F.Fab")
		)
		(fp_line
			(start 0.899922 -1.549908)
			(end 0.899922 -1.199896)
			(stroke
				(width 0.1)
				(type default)
			)
			(layer "F.Fab")
		)
		(fp_line
			(start 0.899922 -1.199896)
			(end 1.599946 -1.199896)
			(stroke
				(width 0.1)
				(type default)
			)
			(layer "F.Fab")
		)
		(fp_line
			(start 0.899922 1.199896)
			(end 0.899922 1.549908)
			(stroke
				(width 0.1)
				(type default)
			)
			(layer "F.Fab")
		)
		(fp_line
			(start 0.899922 1.549908)
			(end -0.899922 1.549908)
			(stroke
				(width 0.1)
				(type default)
			)
			(layer "F.Fab")
		)
		(fp_line
			(start 1.599946 -1.199896)
			(end 1.599946 1.199896)
			(stroke
				(width 0.1)
				(type default)
			)
			(layer "F.Fab")
		)
		(fp_line
			(start 1.599946 1.199896)
			(end 0.899922 1.199896)
			(stroke
				(width 0.1)
				(type default)
			)
			(layer "F.Fab")
		)
		(fp_poly
			(pts
				(xy -2.71272 -0.719328) (xy -2.71272 -1.344168) (xy -2.159 -1.016)
			)
			(stroke
				(width 0)
				(type default)
			)
			(fill yes)
			(layer "F.Fab")
		)
		(pad "1" smd rect
			(at -1.225042 -0.94996 270)
			(size 0.5588 1.3462)
			(layers "F.Cu" "F.Mask" "F.Paste")
			(net "Net_10730")
		)
		(pad "2" smd rect
			(at -1.225042 0 270)
			(size 0.5588 1.3462)
			(layers "F.Cu" "F.Mask" "F.Paste")
			(net "SCM_IRQ_1V8_N")
		)
		(pad "3" smd rect
			(at -1.225042 0.94996 270)
			(size 0.5588 1.3462)
			(layers "F.Cu" "F.Mask" "F.Paste")
			(net "GND")
		)
		(pad "4" smd rect
			(at 1.225042 0.94996 270)
			(size 0.5588 1.3462)
			(layers "F.Cu" "F.Mask" "F.Paste")
			(net "SCM_IRQ_R_N")
		)
		(pad "5" smd rect
			(at 1.225042 -0.94996 270)
			(size 0.5588 1.3462)
			(layers "F.Cu" "F.Mask" "F.Paste")
			(net "P1V8_AUX")
		)
	)
)
